(kicad_pcb
	(version 20241229)
	(generator "pcbnew")
	(generator_version "9.0")
	(general
		(thickness 1.711)
		(legacy_teardrops no)
	)
	(paper "A4")
	(title_block
		(title "Antmicro Baseboard for Jetson AGX Thor")
		(date "2026-02-18")
		(rev "1.1.0")
		(company "Antmicro Ltd")
		(comment 1 "www.antmicro.com")
		(comment 9 "footprints 527-531 of 1170")
	)
	(layers
		(0 "F.Cu" signal)
		(4 "In1.Cu" signal)
		(6 "In2.Cu" signal)
		(8 "In3.Cu" signal)
		(10 "In4.Cu" jumper)
		(12 "In5.Cu" signal)
		(14 "In6.Cu" signal)
		(16 "In7.Cu" signal)
		(18 "In8.Cu" signal)
		(2 "B.Cu" signal)
		(9 "F.Adhes" user "F.Adhesive")
		(11 "B.Adhes" user "B.Adhesive")
		(13 "F.Paste" user)
		(15 "B.Paste" user)
		(5 "F.SilkS" user "F.Silkscreen")
		(7 "B.SilkS" user "B.Silkscreen")
		(1 "F.Mask" user)
		(3 "B.Mask" user)
		(17 "Dwgs.User" user "User.Drawings")
		(19 "Cmts.User" user "User.Comments")
		(21 "Eco1.User" user "User.Eco1")
		(23 "Eco2.User" user "User.Eco2")
		(25 "Edge.Cuts" user)
		(27 "Margin" user)
		(31 "F.CrtYd" user "F.Courtyard")
		(29 "B.CrtYd" user "B.Courtyard")
		(35 "F.Fab" user)
		(33 "B.Fab" user)
	)
	(footprint "antmicro-footprints:TP_SMD_0.75mm"
		(layer "F.Cu")
		(at 203.8 83.2)
		(property "Reference" "TP76"
			(at -2.4 1.6 0)
			(layer "F.SilkS")
			(effects
				(font
					(size 0.7 0.7)
					(thickness 0.15)
				)
				(justify left bottom)
			)
		)
		(property "Value" "TP_0.75mm_SMD"
			(at 0 1.2 0)
			(layer "F.Fab")
			(effects
				(font
					(size 0.7 0.7)
					(thickness 0.15)
				)
				(justify left bottom)
			)
		)
		(property "Description" "SMT test point"
			(at 0 0 0)
			(layer "F.Fab")
			(hide yes)
			(effects
				(font
					(size 1.27 1.27)
					(thickness 0.15)
				)
			)
		)
		(property "MPN" ""
			(at 0 0 0)
			(unlocked yes)
			(layer "F.Fab")
			(hide yes)
			(effects
				(font
					(size 1 1)
					(thickness 0.15)
				)
			)
		)
		(property "Manufacturer" ""
			(at 0 0 0)
			(unlocked yes)
			(layer "F.Fab")
			(hide yes)
			(effects
				(font
					(size 1 1)
					(thickness 0.15)
				)
			)
		)
		(property "Author" "Antmicro"
			(at 0 0 0)
			(unlocked yes)
			(layer "F.Fab")
			(hide yes)
			(effects
				(font
					(size 1 1)
					(thickness 0.15)
				)
			)
		)
		(property "License" "Apache-2.0"
			(at 0 0 0)
			(unlocked yes)
			(layer "F.Fab")
			(hide yes)
			(effects
				(font
					(size 1 1)
					(thickness 0.15)
				)
			)
		)
		(sheetname "/Power/")
		(sheetfile "power.kicad_sch")
		(attr exclude_from_pos_files exclude_from_bom)
		(fp_circle
			(center 0 0)
			(end 0.475 0)
			(stroke
				(width 0.05)
				(type default)
			)
			(fill no)
			(layer "F.CrtYd")
		)
		(fp_text user "Author: Antmicro"
			(at -0.4 3.901 0)
			(layer "F.Fab")
			(effects
				(font
					(size 0.7 0.7)
					(thickness 0.15)
				)
				(justify left bottom)
			)
		)
		(fp_text user "License: Apache-2.0"
			(at -0.4 5.101 0)
			(layer "F.Fab")
			(effects
				(font
					(size 0.7 0.7)
					(thickness 0.15)
				)
				(justify left bottom)
			)
		)
		(fp_text user "${REFERENCE}"
			(at -0.4 2.7 0)
			(layer "F.Fab")
			(effects
				(font
					(size 0.7 0.7)
					(thickness 0.15)
				)
				(justify left bottom)
			)
		)
		(pad "1" smd circle
			(at 0 0)
			(size 0.75 0.75)
			(layers "F.Cu" "F.Mask")
			(net 522 "/Power/USBPD1_HV")
			(pinfunction "1")
			(pintype "passive")
		)
	)
	(footprint "antmicro-footprints:R_0402_1005Metric"
		(layer "F.Cu")
		(at 141.06 58.79 -90)
		(descr "Resistor SMD 0402")
		(tags "resistor SMD 0402")
		(property "Reference" "R416"
			(at 0.97 0.41 90)
			(layer "F.SilkS")
			(effects
				(font
					(size 0.7 0.7)
					(thickness 0.15)
				)
				(justify right top)
			)
		)
		(property "Value" "R_31k6_0402"
			(at -1.011843 1.772046 90)
			(layer "F.Fab")
			(effects
				(font
					(size 0.7 0.7)
					(thickness 0.15)
				)
				(justify right top)
			)
		)
		(property "Datasheet" "https://www.bourns.com/docs/product-datasheets/cr.pdf"
			(at 0 0 90)
			(layer "F.Fab")
			(hide yes)
			(effects
				(font
					(size 1.27 1.27)
					(thickness 0.15)
				)
			)
		)
		(property "Description" "SMD Chip Resistor"
			(at 0 0 90)
			(layer "F.Fab")
			(hide yes)
			(effects
				(font
					(size 1.27 1.27)
					(thickness 0.15)
				)
			)
		)
		(property "MPN" "CR0402-FX-3162GLF"
			(at 0 0 270)
			(unlocked yes)
			(layer "F.Fab")
			(hide yes)
			(effects
				(font
					(size 1 1)
					(thickness 0.15)
				)
			)
		)
		(property "Manufacturer" "Bourns"
			(at 0 0 270)
			(unlocked yes)
			(layer "F.Fab")
			(hide yes)
			(effects
				(font
					(size 1 1)
					(thickness 0.15)
				)
			)
		)
		(property "License" "Apache-2.0"
			(at 0 0 270)
			(unlocked yes)
			(layer "F.Fab")
			(hide yes)
			(effects
				(font
					(size 1 1)
					(thickness 0.15)
				)
			)
		)
		(property "Author" "Antmicro"
			(at 0 0 270)
			(unlocked yes)
			(layer "F.Fab")
			(hide yes)
			(effects
				(font
					(size 1 1)
					(thickness 0.15)
				)
			)
		)
		(property "Val" "31k6"
			(at 0 0 270)
			(unlocked yes)
			(layer "F.Fab")
			(hide yes)
			(effects
				(font
					(size 1 1)
					(thickness 0.15)
				)
			)
		)
		(property "Tolerance" "1%"
			(at 0 0 270)
			(unlocked yes)
			(layer "F.Fab")
			(hide yes)
			(effects
				(font
					(size 1 1)
					(thickness 0.15)
				)
			)
		)
		(sheetname "/Power/")
		(sheetfile "power.kicad_sch")
		(attr smd)
		(fp_poly
			(pts
				(xy -0.925 -0.47) (xy 0.925 -0.47) (xy 0.925 0.47) (xy -0.925 0.47)
			)
			(stroke
				(width 0.05)
				(type default)
			)
			(fill no)
			(layer "F.CrtYd")
		)
		(fp_poly
			(pts
				(xy -0.5 -0.25) (xy 0.5 -0.25) (xy 0.5 0.25) (xy -0.5 0.25)
			)
			(stroke
				(width 0.15)
				(type solid)
			)
			(fill no)
			(layer "F.Fab")
		)
		(fp_text user "${REFERENCE}"
			(at -0.95 3.168 90)
			(layer "F.Fab")
			(effects
				(font
					(size 0.7 0.7)
					(thickness 0.15)
				)
				(justify right top)
			)
		)
		(fp_text user "License: Apache-2.0"
			(at -0.949999 5.169 90)
			(layer "F.Fab")
			(effects
				(font
					(size 0.7 0.7)
					(thickness 0.15)
				)
				(justify right top)
			)
		)
		(fp_text user "Author: Antmicro"
			(at -0.95 4.169 90)
			(layer "F.Fab")
			(effects
				(font
					(size 0.7 0.7)
					(thickness 0.15)
				)
				(justify right top)
			)
		)
		(pad "1" smd roundrect
			(at -0.48 0 270)
			(size 0.59 0.64)
			(layers "F.Cu" "F.Mask" "F.Paste")
			(roundrect_rratio 0.25)
			(net 1396 "Net-(U79-ADJ)")
			(pintype "passive")
		)
		(pad "2" smd roundrect
			(at 0.48 0 270)
			(size 0.59 0.64)
			(layers "F.Cu" "F.Mask" "F.Paste")
			(roundrect_rratio 0.25)
			(net 31 "/Power/3V3_LDO")
			(pintype "passive")
		)
	)
	(footprint "antmicro-footprints:R_0402_1005Metric"
		(layer "F.Cu")
		(at 180.551652 124.197356 -90)
		(descr "Resistor SMD 0402")
		(tags "resistor SMD 0402")
		(property "Reference" "R39"
			(at -6.297356 -3.086529 90)
			(layer "F.SilkS")
			(effects
				(font
					(size 0.7 0.7)
					(thickness 0.15)
				)
				(justify right top)
			)
		)
		(property "Value" "R_499k_0402"
			(at -1.011843 1.772047 90)
			(layer "F.Fab")
			(effects
				(font
					(size 0.7 0.7)
					(thickness 0.15)
				)
				(justify right top)
			)
		)
		(property "Datasheet" "https://www.mouser.com/datasheet/2/54/cr-1858361.pdf"
			(at 0 0 90)
			(layer "F.Fab")
			(hide yes)
			(effects
				(font
					(size 1.27 1.27)
					(thickness 0.15)
				)
			)
		)
		(property "Description" "SMD Chip Resistor, 499 kohm, ± 1%, 63 mW, 0402 [1005 Metric], Thick Film, General Purpose"
			(at 0 0 90)
			(layer "F.Fab")
			(hide yes)
			(effects
				(font
					(size 1.27 1.27)
					(thickness 0.15)
				)
			)
		)
		(property "MPN" "CR0402-FX-4993GLF"
			(at 0 0 270)
			(unlocked yes)
			(layer "F.Fab")
			(hide yes)
			(effects
				(font
					(size 1 1)
					(thickness 0.15)
				)
			)
		)
		(property "Manufacturer" "Bourns"
			(at 0 0 270)
			(unlocked yes)
			(layer "F.Fab")
			(hide yes)
			(effects
				(font
					(size 1 1)
					(thickness 0.15)
				)
			)
		)
		(property "License" "Apache-2.0"
			(at 0 0 270)
			(unlocked yes)
			(layer "F.Fab")
			(hide yes)
			(effects
				(font
					(size 1 1)
					(thickness 0.15)
				)
			)
		)
		(property "Author" "Antmicro"
			(at 0 0 270)
			(unlocked yes)
			(layer "F.Fab")
			(hide yes)
			(effects
				(font
					(size 1 1)
					(thickness 0.15)
				)
			)
		)
		(property "Val" "499k"
			(at 0 0 270)
			(unlocked yes)
			(layer "F.Fab")
			(hide yes)
			(effects
				(font
					(size 1 1)
					(thickness 0.15)
				)
			)
		)
		(property "Tolerance" "1%"
			(at 0 0 270)
			(unlocked yes)
			(layer "F.Fab")
			(hide yes)
			(effects
				(font
					(size 1 1)
					(thickness 0.15)
				)
			)
		)
		(sheetname "/DCDC/")
		(sheetfile "dcdc.kicad_sch")
		(attr smd)
		(fp_rect
			(start -0.925 -0.47)
			(end 0.925 0.47)
			(stroke
				(width 0.05)
				(type default)
			)
			(fill no)
			(layer "F.CrtYd")
		)
		(fp_rect
			(start -0.5 -0.25)
			(end 0.5 0.25)
			(stroke
				(width 0.15)
				(type solid)
			)
			(fill no)
			(layer "F.Fab")
		)
		(fp_text user "${REFERENCE}"
			(at -0.95 3.168 90)
			(layer "F.Fab")
			(effects
				(font
					(size 0.7 0.7)
					(thickness 0.15)
				)
				(justify right top)
			)
		)
		(fp_text user "License: Apache-2.0"
			(at -0.95 5.169 90)
			(layer "F.Fab")
			(effects
				(font
					(size 0.7 0.7)
					(thickness 0.15)
				)
				(justify right top)
			)
		)
		(fp_text user "Author: Antmicro"
			(at -0.95 4.169 90)
			(layer "F.Fab")
			(effects
				(font
					(size 0.7 0.7)
					(thickness 0.15)
				)
				(justify right top)
			)
		)
		(pad "1" smd roundrect
			(at -0.48 0 270)
			(size 0.59 0.64)
			(layers "F.Cu" "F.Mask" "F.Paste")
			(roundrect_rratio 0.25)
			(net 1 "GND")
			(pintype "passive")
		)
		(pad "2" smd roundrect
			(at 0.48 0 270)
			(size 0.59 0.64)
			(layers "F.Cu" "F.Mask" "F.Paste")
			(roundrect_rratio 0.25)
			(net 1213 "/DCDC/3V3_MODE1")
			(pintype "passive")
		)
	)
	(footprint "antmicro-footprints:C_0805_2012Metric"
		(layer "F.Cu")
		(at 169.55 79.81 90)
		(descr "Capacitor SMD 0805")
		(tags "capacitor SMD 0805")
		(property "Reference" "C288"
			(at -4.67 0.23 90)
			(layer "F.SilkS")
			(effects
				(font
					(size 0.7 0.7)
					(thickness 0.15)
				)
				(justify left bottom)
			)
		)
		(property "Value" "C_22u_25V_0805"
			(at -2.055717 1.963152 90)
			(layer "F.Fab")
			(effects
				(font
					(size 0.7 0.7)
					(thickness 0.15)
				)
				(justify left bottom)
			)
		)
		(property "Datasheet" "https://product.samsungsem.com/mlcc/CL21A226MAYNNN.do"
			(at 0 0 90)
			(layer "F.Fab")
			(hide yes)
			(effects
				(font
					(size 1.27 1.27)
					(thickness 0.15)
				)
			)
		)
		(property "Description" "SMT Multilayer Ceramic Capacitor, 22uF, +/-20%, 25V, X5R, 0805 [2012 Metric]"
			(at 0 0 90)
			(layer "F.Fab")
			(hide yes)
			(effects
				(font
					(size 1.27 1.27)
					(thickness 0.15)
				)
			)
		)
		(property "MPN" "CL21A226MAYNNNE"
			(at 0 0 90)
			(unlocked yes)
			(layer "F.Fab")
			(hide yes)
			(effects
				(font
					(size 1 1)
					(thickness 0.15)
				)
			)
		)
		(property "Manufacturer" "Samsung Electro-Mechanics"
			(at 0 0 90)
			(unlocked yes)
			(layer "F.Fab")
			(hide yes)
			(effects
				(font
					(size 1 1)
					(thickness 0.15)
				)
			)
		)
		(property "License" "Apache-2.0"
			(at 0 0 90)
			(unlocked yes)
			(layer "F.Fab")
			(hide yes)
			(effects
				(font
					(size 1 1)
					(thickness 0.15)
				)
			)
		)
		(property "Author" "Antmicro"
			(at 0 0 90)
			(unlocked yes)
			(layer "F.Fab")
			(hide yes)
			(effects
				(font
					(size 1 1)
					(thickness 0.15)
				)
			)
		)
		(property "Val" "22u"
			(at 0 0 90)
			(unlocked yes)
			(layer "F.Fab")
			(hide yes)
			(effects
				(font
					(size 1 1)
					(thickness 0.15)
				)
			)
		)
		(property "Voltage" "25V"
			(at 0 0 90)
			(unlocked yes)
			(layer "F.Fab")
			(hide yes)
			(effects
				(font
					(size 1 1)
					(thickness 0.15)
				)
			)
		)
		(property "Dielectric" "X5R"
			(at 0 0 90)
			(unlocked yes)
			(layer "F.Fab")
			(hide yes)
			(effects
				(font
					(size 1 1)
					(thickness 0.15)
				)
			)
		)
		(property "Public" "False"
			(at 0 0 90)
			(unlocked yes)
			(layer "F.Fab")
			(hide yes)
			(effects
				(font
					(size 1 1)
					(thickness 0.15)
				)
			)
		)
		(component_classes
			(class "DCDC_20V")
		)
		(sheetname "/DCDC/")
		(sheetfile "dcdc.kicad_sch")
		(attr smd)
		(fp_line
			(start -0.3 -0.7)
			(end 0.3 -0.7)
			(stroke
				(width 0.15)
				(type solid)
			)
			(layer "F.SilkS")
		)
		(fp_line
			(start -0.3 0.7)
			(end 0.3 0.7)
			(stroke
				(width 0.15)
				(type solid)
			)
			(layer "F.SilkS")
		)
		(fp_rect
			(start 1.95 -0.9)
			(end -1.95 0.9)
			(stroke
				(width 0.05)
				(type default)
			)
			(fill no)
			(layer "F.CrtYd")
		)
		(fp_rect
			(start -0.95 -0.675)
			(end 0.95 0.675)
			(stroke
				(width 0.15)
				(type solid)
			)
			(fill no)
			(layer "F.Fab")
		)
		(fp_text user "Author: Antmicro"
			(at -1.9 5.947 90)
			(layer "F.Fab")
			(effects
				(font
					(size 0.7 0.7)
					(thickness 0.15)
				)
				(justify left bottom)
			)
		)
		(fp_text user "License: Apache-2.0"
			(at -1.9 4.947 90)
			(layer "F.Fab")
			(effects
				(font
					(size 0.7 0.7)
					(thickness 0.15)
				)
				(justify left bottom)
			)
		)
		(fp_text user "${REFERENCE}"
			(at -1.9 3.947 90)
			(layer "F.Fab")
			(effects
				(font
					(size 0.7 0.7)
					(thickness 0.15)
				)
				(justify left bottom)
			)
		)
		(pad "1" smd roundrect
			(at -1.1 0 90)
			(size 1.2 1.3)
			(layers "F.Cu" "F.Mask" "F.Paste")
			(roundrect_rratio 0.25)
			(net 1 "GND")
			(pintype "passive")
		)
		(pad "2" smd roundrect
			(at 1.1 0 90)
			(size 1.2 1.3)
			(layers "F.Cu" "F.Mask" "F.Paste")
			(roundrect_rratio 0.25)
			(net 1105 "/DCDC/20V_OUT")
			(pintype "passive")
		)
	)
	(footprint "antmicro-footprints:USON-10_2.5x1mm_P0.5mm"
		(layer "F.Cu")
		(at 228 82)
		(descr "USON-10 2.5x1mm_ Pitch 0.5mm")
		(tags "USON-10 2.5x1mm Pitch 0.5mm")
		(property "Reference" "U42"
			(at -1 1.123 90)
			(layer "F.SilkS")
			(effects
				(font
					(size 0.7 0.7)
					(thickness 0.15)
				)
				(justify left bottom)
			)
		)
		(property "Value" "TPD4E05U06QDQARQ1"
			(at 0.018 2.499 0)
			(layer "F.Fab")
			(effects
				(font
					(size 0.7 0.7)
					(thickness 0.15)
				)
				(justify left bottom)
			)
		)
		(property "Datasheet" "https://www.ti.com/lit/ds/symlink/tpd4e05u06-q1.pdf?HQS=dis-mous-null-mousermode-dsf-pf-null-wwe&ts=1663591265741&ref_url=https%253A%252F%252Fwww.mouser.com%252F"
			(at 0 0 0)
			(layer "F.Fab")
			(hide yes)
			(effects
				(font
					(size 1.27 1.27)
					(thickness 0.15)
				)
			)
		)
		(property "Description" "TVS diode array, 12 kV, USON-10, 5.5 V, 0.5 pF"
			(at 0 0 0)
			(layer "F.Fab")
			(hide yes)
			(effects
				(font
					(size 1.27 1.27)
					(thickness 0.15)
				)
			)
		)
		(property "Manufacturer" "Texas Instruments"
			(at 0 0 0)
			(unlocked yes)
			(layer "F.Fab")
			(hide yes)
			(effects
				(font
					(size 1 1)
					(thickness 0.15)
				)
			)
		)
		(property "MPN" "TPD4E05U06QDQARQ1"
			(at 0 0 0)
			(unlocked yes)
			(layer "F.Fab")
			(hide yes)
			(effects
				(font
					(size 1 1)
					(thickness 0.15)
				)
			)
		)
		(property "Author" "Antmicro"
			(at 0 0 0)
			(unlocked yes)
			(layer "F.Fab")
			(hide yes)
			(effects
				(font
					(size 1 1)
					(thickness 0.15)
				)
			)
		)
		(property "License" "Apache-2.0"
			(at 0 0 0)
			(unlocked yes)
			(layer "F.Fab")
			(hide yes)
			(effects
				(font
					(size 1 1)
					(thickness 0.15)
				)
			)
		)
		(sheetname "/USB Debug, PD/")
		(sheetfile "usb_debug_pd.kicad_sch")
		(attr smd)
		(fp_line
			(start 0.498 -1.401)
			(end -0.5 -1.401)
			(stroke
				(width 0.15)
				(type solid)
			)
			(layer "F.SilkS")
		)
		(fp_line
			(start 0.498 1.398)
			(end -0.5 1.398)
			(stroke
				(width 0.15)
				(type solid)
			)
			(layer "F.SilkS")
		)
		(fp_circle
			(center -0.68 -1.27)
			(end -0.63 -1.27)
			(stroke
				(width 0.15)
				(type solid)
			)
			(fill yes)
			(layer "F.SilkS")
		)
		(fp_poly
			(pts
				(xy -0.8 -1.5) (xy 0.8 -1.5) (xy 0.799999 1.499) (xy -0.799999 1.499)
			)
			(stroke
				(width 0.05)
				(type solid)
			)
			(fill no)
			(layer "F.CrtYd")
		)
		(fp_line
			(start -0.5 -1)
			(end -0.5 1.249)
			(stroke
				(width 0.15)
				(type solid)
			)
			(layer "F.Fab")
		)
		(fp_line
			(start -0.5 1.249)
			(end 0.498 1.249)
			(stroke
				(width 0.15)
				(type solid)
			)
			(layer "F.Fab")
		)
		(fp_line
			(start -0.25 -1.25)
			(end -0.5 -1)
			(stroke
				(width 0.15)
				(type solid)
			)
			(layer "F.Fab")
		)
		(fp_line
			(start 0.498 -1.25)
			(end -0.25 -1.25)
			(stroke
				(width 0.15)
				(type solid)
			)
			(layer "F.Fab")
		)
		(fp_line
			(start 0.498 -1.25)
			(end 0.498 1.249)
			(stroke
				(width 0.15)
				(type solid)
			)
			(layer "F.Fab")
		)
		(fp_text user "${REFERENCE}"
			(at -0.802 4.498 0)
			(layer "F.Fab")
			(effects
				(font
					(size 0.7 0.7)
					(thickness 0.15)
				)
				(justify left bottom)
			)
		)
		(fp_text user "Author: Antmicro"
			(at -0.802 5.7 0)
			(layer "F.Fab")
			(effects
				(font
					(size 0.7 0.7)
					(thickness 0.15)
				)
				(justify left bottom)
			)
		)
		(fp_text user "License: Apache-2.0"
			(at -0.802 6.9 0)
			(layer "F.Fab")
			(effects
				(font
					(size 0.7 0.7)
					(thickness 0.15)
				)
				(justify left bottom)
			)
		)
		(pad "1" smd roundrect
			(at -0.387 -1 270)
			(size 0.25 0.55)
			(layers "F.Cu" "F.Mask" "F.Paste")
			(roundrect_rratio 0.25)
			(net 514 "/USB Debug, PD/USBC0_CC1")
			(pintype "passive")
		)
		(pad "2" smd roundrect
			(at -0.387 -0.5 270)
			(size 0.25 0.55)
			(layers "F.Cu" "F.Mask" "F.Paste")
			(roundrect_rratio 0.25)
			(net 488 "/USB Debug, PD/USBC0_D_N")
			(pintype "passive")
		)
		(pad "3" smd roundrect
			(at -0.387 0 270)
			(size 0.4 0.55)
			(layers "F.Cu" "F.Mask" "F.Paste")
			(roundrect_rratio 0.25)
			(net 1 "GND")
			(pintype "power_in")
		)
		(pad "4" smd roundrect
			(at -0.387 0.498 270)
			(size 0.25 0.55)
			(layers "F.Cu" "F.Mask" "F.Paste")
			(roundrect_rratio 0.25)
			(net 489 "/USB Debug, PD/USBC0_D_P")
			(pintype "passive")
		)
		(pad "5" smd roundrect
			(at -0.387 0.998 270)
			(size 0.25 0.55)
			(layers "F.Cu" "F.Mask" "F.Paste")
			(roundrect_rratio 0.25)
			(net 515 "/USB Debug, PD/USBC0_CC2")
			(pintype "passive")
		)
		(pad "6" smd roundrect
			(at 0.385001 0.998 270)
			(size 0.25 0.55)
			(layers "F.Cu" "F.Mask" "F.Paste")
			(roundrect_rratio 0.25)
			(net 515 "/USB Debug, PD/USBC0_CC2")
			(pintype "passive")
		)
		(pad "7" smd roundrect
			(at 0.385 0.498 270)
			(size 0.25 0.55)
			(layers "F.Cu" "F.Mask" "F.Paste")
			(roundrect_rratio 0.25)
			(net 489 "/USB Debug, PD/USBC0_D_P")
			(pintype "passive")
		)
		(pad "8" smd roundrect
			(at 0.385 0 270)
			(size 0.4 0.55)
			(layers "F.Cu" "F.Mask" "F.Paste")
			(roundrect_rratio 0.25)
			(net 1 "GND")
			(pintype "passive")
		)
		(pad "9" smd roundrect
			(at 0.385001 -0.5 270)
			(size 0.25 0.55)
			(layers "F.Cu" "F.Mask" "F.Paste")
			(roundrect_rratio 0.25)
			(net 488 "/USB Debug, PD/USBC0_D_N")
			(pintype "passive")
		)
		(pad "10" smd roundrect
			(at 0.385 -1 270)
			(size 0.25 0.55)
			(layers "F.Cu" "F.Mask" "F.Paste")
			(roundrect_rratio 0.25)
			(net 514 "/USB Debug, PD/USBC0_CC1")
			(pintype "passive")
		)
	)
)
